(kicad_pcb
	(version 20241229)
	(generator "pcbnew")
	(generator_version "9.0")
	(general
		(thickness 1.6642)
		(legacy_teardrops no)
	)
	(paper "A3")
	(title_block
		(title "PolarFire SoM")
		(date "2025-07-22")
		(rev "1.1.4")
		(company "Antmicro Ltd")
		(comment 1 "www.antmicro.com")
		(comment 9 "footprints 246-249 of 470")
	)
	(layers
		(0 "F.Cu" mixed)
		(4 "In1.Cu" power)
		(6 "In2.Cu" signal)
		(8 "In3.Cu" power)
		(10 "In4.Cu" signal)
		(12 "In5.Cu" power)
		(14 "In6.Cu" power)
		(16 "In7.Cu" signal)
		(18 "In8.Cu" power)
		(20 "In9.Cu" signal)
		(22 "In10.Cu" power)
		(24 "In11.Cu" signal)
		(26 "In12.Cu" signal)
		(2 "B.Cu" mixed)
		(9 "F.Adhes" user "F.Adhesive")
		(11 "B.Adhes" user "B.Adhesive")
		(13 "F.Paste" user)
		(15 "B.Paste" user)
		(5 "F.SilkS" user "F.Silkscreen")
		(7 "B.SilkS" user "B.Silkscreen")
		(1 "F.Mask" user)
		(3 "B.Mask" user)
		(17 "Dwgs.User" user "User.Drawings")
		(19 "Cmts.User" user "User.Comments")
		(21 "Eco1.User" user "User.Eco1")
		(23 "Eco2.User" user "User.Eco2")
		(25 "Edge.Cuts" user)
		(27 "Margin" user)
		(31 "F.CrtYd" user "F.Courtyard")
		(29 "B.CrtYd" user "B.Courtyard")
		(35 "F.Fab" user)
		(33 "B.Fab" user)
	)
	(footprint "antmicro-footprints:C_0402_1005Metric"
		(layer "B.Cu")
		(at 211.7266 118.37)
		(descr "Capacitor SMD 0402")
		(tags "capacitor SMD 0402")
		(property "Reference" "C260"
			(at -1.7016 -0.42 0)
			(layer "B.SilkS")
			(effects
				(font
					(size 0.7 0.7)
					(thickness 0.15)
				)
				(justify right bottom mirror)
			)
		)
		(property "Value" "C_100n_0402"
			(at -1.022927 -2.155213 0)
			(layer "B.Fab")
			(hide yes)
			(effects
				(font
					(size 0.7 0.7)
					(thickness 0.15)
				)
				(justify right bottom mirror)
			)
		)
		(property "Datasheet" "https://www.murata.com/products/productdetail?partno=GRM155R61H104KE14%23"
			(at 0 0 0)
			(layer "F.Fab")
			(hide yes)
			(effects
				(font
					(size 1.27 1.27)
					(thickness 0.15)
				)
			)
		)
		(property "Description" "SMD Multilayer Ceramic Capacitor, 0.1 µF, 50 V, 0402 [1005 Metric], ± 10%, X5R, GRM Series"
			(at 0 0 0)
			(layer "F.Fab")
			(hide yes)
			(effects
				(font
					(size 1.27 1.27)
					(thickness 0.15)
				)
			)
		)
		(property "Author" "Antmicro"
			(at 0 0 0)
			(layer "B.Fab")
			(hide yes)
			(effects
				(font
					(size 1 1)
					(thickness 0.15)
				)
				(justify mirror)
			)
		)
		(property "Dielectric" "X5R"
			(at 0 0 0)
			(layer "B.Fab")
			(hide yes)
			(effects
				(font
					(size 1 1)
					(thickness 0.15)
				)
				(justify mirror)
			)
		)
		(property "License" "Apache-2.0"
			(at 0 0 0)
			(layer "B.Fab")
			(hide yes)
			(effects
				(font
					(size 1 1)
					(thickness 0.15)
				)
				(justify mirror)
			)
		)
		(property "MPN" "GRM155R61H104KE14D"
			(at 0 0 0)
			(layer "B.Fab")
			(hide yes)
			(effects
				(font
					(size 1 1)
					(thickness 0.15)
				)
				(justify mirror)
			)
		)
		(property "Manufacturer" "Murata"
			(at 0 0 0)
			(layer "B.Fab")
			(hide yes)
			(effects
				(font
					(size 1 1)
					(thickness 0.15)
				)
				(justify mirror)
			)
		)
		(property "Public" ""
			(at 0 0 0)
			(layer "B.Fab")
			(hide yes)
			(effects
				(font
					(size 1 1)
					(thickness 0.15)
				)
				(justify mirror)
			)
		)
		(property "Val" "100n"
			(at 0 0 0)
			(layer "B.Fab")
			(hide yes)
			(effects
				(font
					(size 1 1)
					(thickness 0.15)
				)
				(justify mirror)
			)
		)
		(property "Voltage" "50V"
			(at 0 0 0)
			(layer "B.Fab")
			(hide yes)
			(effects
				(font
					(size 1 1)
					(thickness 0.15)
				)
				(justify mirror)
			)
		)
		(sheetname "/Ethernet/")
		(sheetfile "ethernet.kicad_sch")
		(attr smd)
		(fp_rect
			(start -0.925 0.47)
			(end 0.925 -0.47)
			(stroke
				(width 0.05)
				(type default)
			)
			(fill no)
			(layer "B.CrtYd")
		)
		(fp_line
			(start -0.494 -0.248)
			(end -0.494 0.25)
			(stroke
				(width 0.15)
				(type solid)
			)
			(layer "B.Fab")
		)
		(fp_line
			(start -0.494 0.25)
			(end 0.504 0.25)
			(stroke
				(width 0.15)
				(type solid)
			)
			(layer "B.Fab")
		)
		(fp_line
			(start 0.504 -0.248)
			(end -0.494 -0.248)
			(stroke
				(width 0.15)
				(type solid)
			)
			(layer "B.Fab")
		)
		(fp_line
			(start 0.504 0.25)
			(end 0.504 -0.248)
			(stroke
				(width 0.15)
				(type solid)
			)
			(layer "B.Fab")
		)
		(fp_text user "${REFERENCE}"
			(at -0.939 -4.599 180)
			(layer "B.Fab")
			(effects
				(font
					(size 0.7 0.7)
					(thickness 0.15)
				)
				(justify left bottom mirror)
			)
		)
		(fp_text user "Author: Antmicro"
			(at -0.939 -3.399 180)
			(layer "B.Fab")
			(effects
				(font
					(size 0.7 0.7)
					(thickness 0.15)
				)
				(justify left bottom mirror)
			)
		)
		(fp_text user "License: Apache-2.0"
			(at -0.939 -5.799 180)
			(layer "B.Fab")
			(effects
				(font
					(size 0.7 0.7)
					(thickness 0.15)
				)
				(justify left bottom mirror)
			)
		)
		(pad "1" smd roundrect
			(at -0.48 0)
			(size 0.59 0.64)
			(layers "B.Cu" "B.Mask" "B.Paste")
			(roundrect_rratio 0.25)
			(net 43 "/Ethernet/SGMII.TX0_P")
			(pintype "passive")
		)
		(pad "2" smd roundrect
			(at 0.48 0)
			(size 0.59 0.64)
			(layers "B.Cu" "B.Mask" "B.Paste")
			(roundrect_rratio 0.25)
			(net 164 "/Ethernet/SGMII_SI_P")
			(pintype "passive")
		)
	)
	(footprint "antmicro-footprints:C_0402_1005Metric"
		(layer "B.Cu")
		(at 203.36 145.416 180)
		(descr "Capacitor SMD 0402")
		(tags "capacitor SMD 0402")
		(property "Reference" "C199"
			(at -1.47 0.526 0)
			(layer "B.SilkS")
			(effects
				(font
					(size 0.7 0.7)
					(thickness 0.15)
				)
				(justify left bottom mirror)
			)
		)
		(property "Value" "C_100n_0402"
			(at -1.022927 -2.155213 0)
			(layer "B.Fab")
			(hide yes)
			(effects
				(font
					(size 0.7 0.7)
					(thickness 0.15)
				)
				(justify left bottom mirror)
			)
		)
		(property "Datasheet" "https://www.murata.com/products/productdetail?partno=GRM155R61H104KE14%23"
			(at 0 0 180)
			(layer "F.Fab")
			(hide yes)
			(effects
				(font
					(size 1.27 1.27)
					(thickness 0.15)
				)
			)
		)
		(property "Description" "SMD Multilayer Ceramic Capacitor, 0.1 µF, 50 V, 0402 [1005 Metric], ± 10%, X5R, GRM Series"
			(at 0 0 180)
			(layer "F.Fab")
			(hide yes)
			(effects
				(font
					(size 1.27 1.27)
					(thickness 0.15)
				)
			)
		)
		(property "Author" "Antmicro"
			(at 406.72 290.832 0)
			(layer "B.Fab")
			(hide yes)
			(effects
				(font
					(size 1 1)
					(thickness 0.15)
				)
				(justify mirror)
			)
		)
		(property "Dielectric" "X5R"
			(at 406.72 290.832 0)
			(layer "B.Fab")
			(hide yes)
			(effects
				(font
					(size 1 1)
					(thickness 0.15)
				)
				(justify mirror)
			)
		)
		(property "License" "Apache-2.0"
			(at 406.72 290.832 0)
			(layer "B.Fab")
			(hide yes)
			(effects
				(font
					(size 1 1)
					(thickness 0.15)
				)
				(justify mirror)
			)
		)
		(property "MPN" "GRM155R61H104KE14D"
			(at 406.72 290.832 0)
			(layer "B.Fab")
			(hide yes)
			(effects
				(font
					(size 1 1)
					(thickness 0.15)
				)
				(justify mirror)
			)
		)
		(property "Manufacturer" "Murata"
			(at 406.72 290.832 0)
			(layer "B.Fab")
			(hide yes)
			(effects
				(font
					(size 1 1)
					(thickness 0.15)
				)
				(justify mirror)
			)
		)
		(property "Public" ""
			(at 406.72 290.832 0)
			(layer "B.Fab")
			(hide yes)
			(effects
				(font
					(size 1 1)
					(thickness 0.15)
				)
				(justify mirror)
			)
		)
		(property "Val" "100n"
			(at 406.72 290.832 0)
			(layer "B.Fab")
			(hide yes)
			(effects
				(font
					(size 1 1)
					(thickness 0.15)
				)
				(justify mirror)
			)
		)
		(property "Voltage" "50V"
			(at 406.72 290.832 0)
			(layer "B.Fab")
			(hide yes)
			(effects
				(font
					(size 1 1)
					(thickness 0.15)
				)
				(justify mirror)
			)
		)
		(sheetname "/MIPI CrossLink/")
		(sheetfile "crosslink.kicad_sch")
		(attr smd)
		(fp_rect
			(start -0.925 0.47)
			(end 0.925 -0.47)
			(stroke
				(width 0.05)
				(type default)
			)
			(fill no)
			(layer "B.CrtYd")
		)
		(fp_line
			(start 0.504 0.25)
			(end 0.504 -0.248)
			(stroke
				(width 0.15)
				(type solid)
			)
			(layer "B.Fab")
		)
		(fp_line
			(start 0.504 -0.248)
			(end -0.494 -0.248)
			(stroke
				(width 0.15)
				(type solid)
			)
			(layer "B.Fab")
		)
		(fp_line
			(start -0.494 0.25)
			(end 0.504 0.25)
			(stroke
				(width 0.15)
				(type solid)
			)
			(layer "B.Fab")
		)
		(fp_line
			(start -0.494 -0.248)
			(end -0.494 0.25)
			(stroke
				(width 0.15)
				(type solid)
			)
			(layer "B.Fab")
		)
		(fp_text user "License: Apache-2.0"
			(at -0.939 -5.799 0)
			(layer "B.Fab")
			(effects
				(font
					(size 0.7 0.7)
					(thickness 0.15)
				)
				(justify left bottom mirror)
			)
		)
		(fp_text user "${REFERENCE}"
			(at -0.939 -4.599 0)
			(layer "B.Fab")
			(effects
				(font
					(size 0.7 0.7)
					(thickness 0.15)
				)
				(justify left bottom mirror)
			)
		)
		(fp_text user "Author: Antmicro"
			(at -0.939 -3.399 0)
			(layer "B.Fab")
			(effects
				(font
					(size 0.7 0.7)
					(thickness 0.15)
				)
				(justify left bottom mirror)
			)
		)
		(pad "1" smd roundrect
			(at -0.48 0 180)
			(size 0.59 0.64)
			(layers "B.Cu" "B.Mask" "B.Paste")
			(roundrect_rratio 0.25)
			(net 417 "GND")
			(pintype "passive")
		)
		(pad "2" smd roundrect
			(at 0.48 0 180)
			(size 0.59 0.64)
			(layers "B.Cu" "B.Mask" "B.Paste")
			(roundrect_rratio 0.25)
			(net 180 "/MIPI CrossLink/CL_VCCGPLL")
			(pintype "passive")
		)
	)
	(footprint "antmicro-footprints:R_0402_1005Metric"
		(layer "B.Cu")
		(at 210.1775 135.347)
		(descr "Resistor SMD 0402")
		(tags "resistor SMD 0402")
		(property "Reference" "R29"
			(at 1.6225 3.353 180)
			(layer "B.SilkS")
			(effects
				(font
					(size 0.7 0.7)
					(thickness 0.15)
				)
				(justify left bottom mirror)
			)
		)
		(property "Value" "R_10k_0402"
			(at -1.011843 -1.772047 180)
			(layer "B.Fab")
			(hide yes)
			(effects
				(font
					(size 0.7 0.7)
					(thickness 0.15)
				)
				(justify left bottom mirror)
			)
		)
		(property "Datasheet" "https://www.bourns.com/docs/product-datasheets/cr.pdf"
			(at 0 0 0)
			(layer "F.Fab")
			(hide yes)
			(effects
				(font
					(size 1.27 1.27)
					(thickness 0.15)
				)
			)
		)
		(property "Description" "SMD Chip Resistor, 10 kohm, ± 1%, 62.5 mW, 0402 [1005 Metric], Thick Film, General Purpose"
			(at 0 0 0)
			(layer "F.Fab")
			(hide yes)
			(effects
				(font
					(size 1.27 1.27)
					(thickness 0.15)
				)
			)
		)
		(property "Author" "Antmicro"
			(at 0 0 0)
			(layer "B.Fab")
			(hide yes)
			(effects
				(font
					(size 1 1)
					(thickness 0.15)
				)
				(justify mirror)
			)
		)
		(property "License" "Apache-2.0"
			(at 0 0 0)
			(layer "B.Fab")
			(hide yes)
			(effects
				(font
					(size 1 1)
					(thickness 0.15)
				)
				(justify mirror)
			)
		)
		(property "MPN" "CR0402-FX-1002GLF"
			(at 0 0 0)
			(layer "B.Fab")
			(hide yes)
			(effects
				(font
					(size 1 1)
					(thickness 0.15)
				)
				(justify mirror)
			)
		)
		(property "Manufacturer" "Bourns"
			(at 0 0 0)
			(layer "B.Fab")
			(hide yes)
			(effects
				(font
					(size 1 1)
					(thickness 0.15)
				)
				(justify mirror)
			)
		)
		(property "Public" ""
			(at 0 0 0)
			(layer "B.Fab")
			(hide yes)
			(effects
				(font
					(size 1 1)
					(thickness 0.15)
				)
				(justify mirror)
			)
		)
		(property "Tolerance" "1%"
			(at 0 0 0)
			(layer "B.Fab")
			(hide yes)
			(effects
				(font
					(size 1 1)
					(thickness 0.15)
				)
				(justify mirror)
			)
		)
		(property "Val" "10k"
			(at 0 0 0)
			(layer "B.Fab")
			(hide yes)
			(effects
				(font
					(size 1 1)
					(thickness 0.15)
				)
				(justify mirror)
			)
		)
		(sheetname "/Memory/")
		(sheetfile "memory.kicad_sch")
		(attr smd)
		(fp_rect
			(start -0.925 0.47)
			(end 0.925 -0.47)
			(stroke
				(width 0.05)
				(type default)
			)
			(fill no)
			(layer "B.CrtYd")
		)
		(fp_rect
			(start -0.5 0.25)
			(end 0.5 -0.25)
			(stroke
				(width 0.15)
				(type solid)
			)
			(fill no)
			(layer "B.Fab")
		)
		(fp_text user "${REFERENCE}"
			(at -0.95 -3.168 180)
			(layer "B.Fab")
			(effects
				(font
					(size 0.7 0.7)
					(thickness 0.15)
				)
				(justify left bottom mirror)
			)
		)
		(fp_text user "Author: Antmicro"
			(at -0.95 -4.169 180)
			(layer "B.Fab")
			(effects
				(font
					(size 0.7 0.7)
					(thickness 0.15)
				)
				(justify left bottom mirror)
			)
		)
		(fp_text user "License: Apache-2.0"
			(at -0.95 -5.169 180)
			(layer "B.Fab")
			(effects
				(font
					(size 0.7 0.7)
					(thickness 0.15)
				)
				(justify left bottom mirror)
			)
		)
		(pad "1" smd roundrect
			(at -0.48 0)
			(size 0.59 0.64)
			(layers "B.Cu" "B.Mask" "B.Paste")
			(roundrect_rratio 0.25)
			(net 391 "/FPGA MSSIO/EMMC.CMD")
			(pintype "passive")
		)
		(pad "2" smd roundrect
			(at 0.48 0)
			(size 0.59 0.64)
			(layers "B.Cu" "B.Mask" "B.Paste")
			(roundrect_rratio 0.25)
			(net 137 "SD_VDD")
			(pintype "passive")
		)
	)
	(footprint "antmicro-footprints:R_0402_1005Metric"
		(layer "B.Cu")
		(at 223.4 125.945 -90)
		(descr "Resistor SMD 0402")
		(tags "resistor SMD 0402")
		(property "Reference" "R46"
			(at -1.345 -2.475 90)
			(layer "B.SilkS")
			(effects
				(font
					(size 0.7 0.7)
					(thickness 0.15)
				)
				(justify left bottom mirror)
			)
		)
		(property "Value" "R_10k_0402"
			(at -1.011843 -1.772047 90)
			(layer "B.Fab")
			(hide yes)
			(effects
				(font
					(size 0.7 0.7)
					(thickness 0.15)
				)
				(justify left bottom mirror)
			)
		)
		(property "Datasheet" "https://www.bourns.com/docs/product-datasheets/cr.pdf"
			(at 0 0 270)
			(layer "F.Fab")
			(hide yes)
			(effects
				(font
					(size 1.27 1.27)
					(thickness 0.15)
				)
			)
		)
		(property "Description" "SMD Chip Resistor, 10 kohm, ± 1%, 62.5 mW, 0402 [1005 Metric], Thick Film, General Purpose"
			(at 0 0 270)
			(layer "F.Fab")
			(hide yes)
			(effects
				(font
					(size 1.27 1.27)
					(thickness 0.15)
				)
			)
		)
		(property "Author" "Antmicro"
			(at 97.455 349.345 0)
			(layer "B.Fab")
			(hide yes)
			(effects
				(font
					(size 1 1)
					(thickness 0.15)
				)
				(justify mirror)
			)
		)
		(property "License" "Apache-2.0"
			(at 97.455 349.345 0)
			(layer "B.Fab")
			(hide yes)
			(effects
				(font
					(size 1 1)
					(thickness 0.15)
				)
				(justify mirror)
			)
		)
		(property "MPN" "CR0402-FX-1002GLF"
			(at 97.455 349.345 0)
			(layer "B.Fab")
			(hide yes)
			(effects
				(font
					(size 1 1)
					(thickness 0.15)
				)
				(justify mirror)
			)
		)
		(property "Manufacturer" "Bourns"
			(at 97.455 349.345 0)
			(layer "B.Fab")
			(hide yes)
			(effects
				(font
					(size 1 1)
					(thickness 0.15)
				)
				(justify mirror)
			)
		)
		(property "Public" ""
			(at 97.455 349.345 0)
			(layer "B.Fab")
			(hide yes)
			(effects
				(font
					(size 1 1)
					(thickness 0.15)
				)
				(justify mirror)
			)
		)
		(property "Tolerance" "1%"
			(at 97.455 349.345 0)
			(layer "B.Fab")
			(hide yes)
			(effects
				(font
					(size 1 1)
					(thickness 0.15)
				)
				(justify mirror)
			)
		)
		(property "Val" "10k"
			(at 97.455 349.345 0)
			(layer "B.Fab")
			(hide yes)
			(effects
				(font
					(size 1 1)
					(thickness 0.15)
				)
				(justify mirror)
			)
		)
		(sheetname "/FPGA Config/")
		(sheetfile "fpga-config.kicad_sch")
		(attr smd)
		(fp_rect
			(start -0.925 0.47)
			(end 0.925 -0.47)
			(stroke
				(width 0.05)
				(type default)
			)
			(fill no)
			(layer "B.CrtYd")
		)
		(fp_rect
			(start -0.5 0.25)
			(end 0.5 -0.25)
			(stroke
				(width 0.15)
				(type solid)
			)
			(fill no)
			(layer "B.Fab")
		)
		(fp_text user "Author: Antmicro"
			(at -0.95 -4.169 90)
			(layer "B.Fab")
			(effects
				(font
					(size 0.7 0.7)
					(thickness 0.15)
				)
				(justify left bottom mirror)
			)
		)
		(fp_text user "${REFERENCE}"
			(at -0.95 -3.168 90)
			(layer "B.Fab")
			(effects
				(font
					(size 0.7 0.7)
					(thickness 0.15)
				)
				(justify left bottom mirror)
			)
		)
		(fp_text user "License: Apache-2.0"
			(at -0.95 -5.169 90)
			(layer "B.Fab")
			(effects
				(font
					(size 0.7 0.7)
					(thickness 0.15)
				)
				(justify left bottom mirror)
			)
		)
		(pad "1" smd roundrect
			(at -0.48 0 270)
			(size 0.59 0.64)
			(layers "B.Cu" "B.Mask" "B.Paste")
			(roundrect_rratio 0.25)
			(net 259 "Net-(U3-HOLD#{slash}DQ3)")
			(pintype "passive")
		)
		(pad "2" smd roundrect
			(at 0.48 0 270)
			(size 0.59 0.64)
			(layers "B.Cu" "B.Mask" "B.Paste")
			(roundrect_rratio 0.25)
			(net 50 "+3V3")
			(pintype "passive")
		)
	)
)
